# T6G (Grand Teton) — schematic netlist excerpt (pin names and nets, part order shuffled) for the footprints in the layout excerpt that follows; sources: Cadence DE-HDL packaged netlist, KiCad conversion of 04192023_DAF0TMB3IC0_F0TG_MB_C_brd_V02_OCP.brd

R8248  Q_RES  0 5% CHIP  pkg 0402LF  page 217 : A = SMB_SCM_2_R1_SCL ; B = SMB_CLK_PVDDCR_CPU1_P1_R
PR13  Q_RES  0 5% CHIP  pkg 0402LF  page 224 : A = NC_PVDD11_S3_P1_IMON5 ; B = GND

(kicad_pcb
	(version 20260206)
	(generator "pcbnew")
	(generator_version "10.0")
	(general
		(thickness 1.6)
		(legacy_teardrops no)
	)
	(paper "A4")
	(title_block
		(title "04192023_DAF0TMB3IC0_F0TG_MB_C_brd_V02_OCP.brd")
		(comment 1 "Grand Teton / footprints 2693-2694 of 8354")
	)
	(layers
		(0 "F.Cu" signal "TOP")
		(4 "In1.Cu" signal "GND")
		(6 "In2.Cu" signal "IN1")
		(8 "In3.Cu" signal "GND1")
		(10 "In4.Cu" signal "IN2")
		(12 "In5.Cu" signal "GND2")
		(14 "In6.Cu" signal "IN3")
		(16 "In7.Cu" signal "GND3")
		(18 "In8.Cu" signal "VCC")
		(20 "In9.Cu" signal "VCC1")
		(22 "In10.Cu" signal "GND4")
		(24 "In11.Cu" signal "IN4")
		(26 "In12.Cu" signal "GND5")
		(28 "In13.Cu" signal "IN5")
		(30 "In14.Cu" signal "GND6")
		(32 "In15.Cu" signal "IN6")
		(34 "In16.Cu" signal "GND7")
		(2 "B.Cu" signal "BOTTOM")
		(9 "F.Adhes" user "F.Adhesive")
		(11 "B.Adhes" user "B.Adhesive")
		(13 "F.Paste" user "Package Geometry/Pastemask Top")
		(15 "B.Paste" user "Package Geometry/Pastemask Bottom")
		(5 "F.SilkS" user "Ref Des/Silkscreen Top")
		(7 "B.SilkS" user "Ref Des/Silkscreen Bottom")
		(1 "F.Mask" user "Board Geometry/Soldermask Top")
		(3 "B.Mask" user "Board Geometry/Soldermask Bottom")
		(17 "Dwgs.User" user "User.Drawings")
		(19 "Cmts.User" user "User.Comments")
		(21 "Eco1.User" user "User.Eco1")
		(23 "Eco2.User" user "User.Eco2")
		(25 "Edge.Cuts" user "Board Geometry/Outline")
		(27 "Margin" user)
		(31 "F.CrtYd" user "Package Geometry/Place Bound Top")
		(29 "B.CrtYd" user "Package Geometry/Place Bound Bottom")
		(35 "F.Fab" user "Ref Des/Assembly Top")
		(33 "B.Fab" user "Ref Des/Assembly Bottom")
	)
	(footprint ""
		(layer "F.Cu")
		(at 24.765 -366.903)
		(property "Reference" "R8248"
			(at 0 0 0)
			(layer "F.SilkS")
			(hide yes)
			(effects
				(font
					(size 1.27 1.27)
				)
			)
		)
		(property "Value" ""
			(at 0 0 0)
			(layer "F.Fab")
			(effects
				(font
					(size 1.27 1.27)
				)
			)
		)
		(duplicate_pad_numbers_are_jumpers no)
		(fp_line
			(start -0.7874 -0.4064)
			(end 0.7874 -0.4064)
			(stroke
				(width 0.1524)
				(type default)
			)
			(layer "F.SilkS")
		)
		(fp_line
			(start -0.7874 0.4064)
			(end -0.7874 -0.4064)
			(stroke
				(width 0.1524)
				(type default)
			)
			(layer "F.SilkS")
		)
		(fp_line
			(start 0.7874 -0.4064)
			(end 0.7874 0.4064)
			(stroke
				(width 0.1524)
				(type default)
			)
			(layer "F.SilkS")
		)
		(fp_line
			(start 0.7874 0.4064)
			(end -0.7874 0.4064)
			(stroke
				(width 0.1524)
				(type default)
			)
			(layer "F.SilkS")
		)
		(fp_line
			(start -0.67945 -0.305054)
			(end -0.12065 -0.305054)
			(stroke
				(width 0.1)
				(type default)
			)
			(layer "F.Fab")
		)
		(fp_line
			(start -0.67945 0.3048)
			(end -0.67945 -0.305054)
			(stroke
				(width 0.1)
				(type default)
			)
			(layer "F.Fab")
		)
		(fp_line
			(start -0.12065 -0.305054)
			(end -0.12065 -0.2794)
			(stroke
				(width 0.1)
				(type default)
			)
			(layer "F.Fab")
		)
		(fp_line
			(start -0.12065 -0.2794)
			(end 0.12065 -0.2794)
			(stroke
				(width 0.1)
				(type default)
			)
			(layer "F.Fab")
		)
		(fp_line
			(start -0.12065 0.2794)
			(end -0.12065 0.3048)
			(stroke
				(width 0.1)
				(type default)
			)
			(layer "F.Fab")
		)
		(fp_line
			(start -0.12065 0.3048)
			(end -0.67945 0.3048)
			(stroke
				(width 0.1)
				(type default)
			)
			(layer "F.Fab")
		)
		(fp_line
			(start 0.120396 0.2794)
			(end -0.12065 0.2794)
			(stroke
				(width 0.1)
				(type default)
			)
			(layer "F.Fab")
		)
		(fp_line
			(start 0.120396 0.3048)
			(end 0.120396 0.2794)
			(stroke
				(width 0.1)
				(type default)
			)
			(layer "F.Fab")
		)
		(fp_line
			(start 0.12065 -0.3048)
			(end 0.67945 -0.3048)
			(stroke
				(width 0.1)
				(type default)
			)
			(layer "F.Fab")
		)
		(fp_line
			(start 0.12065 -0.2794)
			(end 0.12065 -0.3048)
			(stroke
				(width 0.1)
				(type default)
			)
			(layer "F.Fab")
		)
		(fp_line
			(start 0.67945 -0.3048)
			(end 0.67945 0.3048)
			(stroke
				(width 0.1)
				(type default)
			)
			(layer "F.Fab")
		)
		(fp_line
			(start 0.67945 0.3048)
			(end 0.120396 0.3048)
			(stroke
				(width 0.1)
				(type default)
			)
			(layer "F.Fab")
		)
		(pad "1" smd circle
			(at -0.40005 0)
			(size 0 0)
			(layers "F.Cu" "F.Mask" "F.Paste")
			(net "SMB_SCM_2_R1_SCL")
		)
		(pad "2" smd circle
			(at 0.40005 0)
			(size 0 0)
			(layers "F.Cu" "F.Mask" "F.Paste")
			(net "SMB_CLK_PVDDCR_CPU1_P1_R")
		)
	)
	(footprint ""
		(layer "F.Cu")
		(at 164.143944 -344.153998 -90)
		(property "Reference" "PR13"
			(at 0 0 270)
			(layer "F.SilkS")
			(hide yes)
			(effects
				(font
					(size 1.27 1.27)
				)
			)
		)
		(property "Value" ""
			(at 0 0 270)
			(layer "F.Fab")
			(effects
				(font
					(size 1.27 1.27)
				)
			)
		)
		(duplicate_pad_numbers_are_jumpers no)
		(fp_line
			(start -0.7874 0.4064)
			(end -0.7874 -0.4064)
			(stroke
				(width 0.1524)
				(type default)
			)
			(layer "F.SilkS")
		)
		(fp_line
			(start 0.7874 0.4064)
			(end -0.7874 0.4064)
			(stroke
				(width 0.1524)
				(type default)
			)
			(layer "F.SilkS")
		)
		(fp_line
			(start -0.7874 -0.4064)
			(end 0.7874 -0.4064)
			(stroke
				(width 0.1524)
				(type default)
			)
			(layer "F.SilkS")
		)
		(fp_line
			(start 0.7874 -0.4064)
			(end 0.7874 0.4064)
			(stroke
				(width 0.1524)
				(type default)
			)
			(layer "F.SilkS")
		)
		(fp_line
			(start -0.67945 0.3048)
			(end -0.67945 -0.305054)
			(stroke
				(width 0.1)
				(type default)
			)
			(layer "F.Fab")
		)
		(fp_line
			(start -0.12065 0.3048)
			(end -0.67945 0.3048)
			(stroke
				(width 0.1)
				(type default)
			)
			(layer "F.Fab")
		)
		(fp_line
			(start 0.120396 0.3048)
			(end 0.120396 0.2794)
			(stroke
				(width 0.1)
				(type default)
			)
			(layer "F.Fab")
		)
		(fp_line
			(start 0.67945 0.3048)
			(end 0.120396 0.3048)
			(stroke
				(width 0.1)
				(type default)
			)
			(layer "F.Fab")
		)
		(fp_line
			(start -0.12065 0.2794)
			(end -0.12065 0.3048)
			(stroke
				(width 0.1)
				(type default)
			)
			(layer "F.Fab")
		)
		(fp_line
			(start 0.120396 0.2794)
			(end -0.12065 0.2794)
			(stroke
				(width 0.1)
				(type default)
			)
			(layer "F.Fab")
		)
		(fp_line
			(start -0.12065 -0.2794)
			(end 0.12065 -0.2794)
			(stroke
				(width 0.1)
				(type default)
			)
			(layer "F.Fab")
		)
		(fp_line
			(start 0.12065 -0.2794)
			(end 0.12065 -0.3048)
			(stroke
				(width 0.1)
				(type default)
			)
			(layer "F.Fab")
		)
		(fp_line
			(start 0.12065 -0.3048)
			(end 0.67945 -0.3048)
			(stroke
				(width 0.1)
				(type default)
			)
			(layer "F.Fab")
		)
		(fp_line
			(start 0.67945 -0.3048)
			(end 0.67945 0.3048)
			(stroke
				(width 0.1)
				(type default)
			)
			(layer "F.Fab")
		)
		(fp_line
			(start -0.67945 -0.305054)
			(end -0.12065 -0.305054)
			(stroke
				(width 0.1)
				(type default)
			)
			(layer "F.Fab")
		)
		(fp_line
			(start -0.12065 -0.305054)
			(end -0.12065 -0.2794)
			(stroke
				(width 0.1)
				(type default)
			)
			(layer "F.Fab")
		)
		(pad "1" smd circle
			(at -0.40005 0 270)
			(size 0 0)
			(layers "F.Cu" "F.Mask" "F.Paste")
			(net "NC_PVDD11_S3_P1_IMON5")
		)
		(pad "2" smd circle
			(at 0.40005 0 270)
			(size 0 0)
			(layers "F.Cu" "F.Mask" "F.Paste")
			(net "GND")
		)
	)
)
